# T6G (Grand Teton) — schematic netlist excerpt (pin names and nets, part order shuffled) for the footprints in the layout excerpt that follows; sources: Cadence DE-HDL packaged netlist, KiCad conversion of 04192023_DAF0TMB3IC0_F0TG_MB_C_brd_V02_OCP.brd

R8120  Q_RES  10K 1% CHIP  pkg 0402LF  page 268 : A = P3V3_AUX ; B = UV_P2V5_COMP
R2834  Q_RES  4.7K 5% CHIP  pkg 0402LF  page 127 : A = P3V3_AUX ; B = RST_BMC_FROM_SWB

(kicad_pcb
	(version 20260206)
	(generator "pcbnew")
	(generator_version "10.0")
	(general
		(thickness 1.6)
		(legacy_teardrops no)
	)
	(paper "A4")
	(title_block
		(title "04192023_DAF0TMB3IC0_F0TG_MB_C_brd_V02_OCP.brd")
		(comment 1 "Grand Teton / footprints 3470-3471 of 8354")
	)
	(layers
		(0 "F.Cu" signal "TOP")
		(4 "In1.Cu" signal "GND")
		(6 "In2.Cu" signal "IN1")
		(8 "In3.Cu" signal "GND1")
		(10 "In4.Cu" signal "IN2")
		(12 "In5.Cu" signal "GND2")
		(14 "In6.Cu" signal "IN3")
		(16 "In7.Cu" signal "GND3")
		(18 "In8.Cu" signal "VCC")
		(20 "In9.Cu" signal "VCC1")
		(22 "In10.Cu" signal "GND4")
		(24 "In11.Cu" signal "IN4")
		(26 "In12.Cu" signal "GND5")
		(28 "In13.Cu" signal "IN5")
		(30 "In14.Cu" signal "GND6")
		(32 "In15.Cu" signal "IN6")
		(34 "In16.Cu" signal "GND7")
		(2 "B.Cu" signal "BOTTOM")
		(9 "F.Adhes" user "F.Adhesive")
		(11 "B.Adhes" user "B.Adhesive")
		(13 "F.Paste" user "Package Geometry/Pastemask Top")
		(15 "B.Paste" user "Package Geometry/Pastemask Bottom")
		(5 "F.SilkS" user "Ref Des/Silkscreen Top")
		(7 "B.SilkS" user "Ref Des/Silkscreen Bottom")
		(1 "F.Mask" user "Board Geometry/Soldermask Top")
		(3 "B.Mask" user "Board Geometry/Soldermask Bottom")
		(17 "Dwgs.User" user "User.Drawings")
		(19 "Cmts.User" user "User.Comments")
		(21 "Eco1.User" user "User.Eco1")
		(23 "Eco2.User" user "User.Eco2")
		(25 "Edge.Cuts" user "Board Geometry/Outline")
		(27 "Margin" user)
		(31 "F.CrtYd" user "Package Geometry/Place Bound Top")
		(29 "B.CrtYd" user "Package Geometry/Place Bound Bottom")
		(35 "F.Fab" user "Ref Des/Assembly Top")
		(33 "B.Fab" user "Ref Des/Assembly Bottom")
	)
	(footprint ""
		(layer "F.Cu")
		(at 425.54144 -438.214008 90)
		(property "Reference" "R2834"
			(at 0 0 90)
			(layer "F.SilkS")
			(hide yes)
			(effects
				(font
					(size 1.27 1.27)
				)
			)
		)
		(property "Value" ""
			(at 0 0 90)
			(layer "F.Fab")
			(effects
				(font
					(size 1.27 1.27)
				)
			)
		)
		(duplicate_pad_numbers_are_jumpers no)
		(fp_line
			(start 0.7874 -0.4064)
			(end 0.7874 0.4064)
			(stroke
				(width 0.1524)
				(type default)
			)
			(layer "F.SilkS")
		)
		(fp_line
			(start -0.7874 -0.4064)
			(end 0.7874 -0.4064)
			(stroke
				(width 0.1524)
				(type default)
			)
			(layer "F.SilkS")
		)
		(fp_line
			(start 0.7874 0.4064)
			(end -0.7874 0.4064)
			(stroke
				(width 0.1524)
				(type default)
			)
			(layer "F.SilkS")
		)
		(fp_line
			(start -0.7874 0.4064)
			(end -0.7874 -0.4064)
			(stroke
				(width 0.1524)
				(type default)
			)
			(layer "F.SilkS")
		)
		(fp_line
			(start -0.12065 -0.305054)
			(end -0.12065 -0.2794)
			(stroke
				(width 0.1)
				(type default)
			)
			(layer "F.Fab")
		)
		(fp_line
			(start -0.67945 -0.305054)
			(end -0.12065 -0.305054)
			(stroke
				(width 0.1)
				(type default)
			)
			(layer "F.Fab")
		)
		(fp_line
			(start 0.67945 -0.3048)
			(end 0.67945 0.3048)
			(stroke
				(width 0.1)
				(type default)
			)
			(layer "F.Fab")
		)
		(fp_line
			(start 0.12065 -0.3048)
			(end 0.67945 -0.3048)
			(stroke
				(width 0.1)
				(type default)
			)
			(layer "F.Fab")
		)
		(fp_line
			(start 0.12065 -0.2794)
			(end 0.12065 -0.3048)
			(stroke
				(width 0.1)
				(type default)
			)
			(layer "F.Fab")
		)
		(fp_line
			(start -0.12065 -0.2794)
			(end 0.12065 -0.2794)
			(stroke
				(width 0.1)
				(type default)
			)
			(layer "F.Fab")
		)
		(fp_line
			(start 0.120396 0.2794)
			(end -0.12065 0.2794)
			(stroke
				(width 0.1)
				(type default)
			)
			(layer "F.Fab")
		)
		(fp_line
			(start -0.12065 0.2794)
			(end -0.12065 0.3048)
			(stroke
				(width 0.1)
				(type default)
			)
			(layer "F.Fab")
		)
		(fp_line
			(start 0.67945 0.3048)
			(end 0.120396 0.3048)
			(stroke
				(width 0.1)
				(type default)
			)
			(layer "F.Fab")
		)
		(fp_line
			(start 0.120396 0.3048)
			(end 0.120396 0.2794)
			(stroke
				(width 0.1)
				(type default)
			)
			(layer "F.Fab")
		)
		(fp_line
			(start -0.12065 0.3048)
			(end -0.67945 0.3048)
			(stroke
				(width 0.1)
				(type default)
			)
			(layer "F.Fab")
		)
		(fp_line
			(start -0.67945 0.3048)
			(end -0.67945 -0.305054)
			(stroke
				(width 0.1)
				(type default)
			)
			(layer "F.Fab")
		)
		(pad "1" smd circle
			(at -0.40005 0 90)
			(size 0 0)
			(layers "F.Cu" "F.Mask" "F.Paste")
			(net "P3V3_AUX")
		)
		(pad "2" smd circle
			(at 0.40005 0 90)
			(size 0 0)
			(layers "F.Cu" "F.Mask" "F.Paste")
			(net "RST_BMC_FROM_SWB")
		)
	)
	(footprint ""
		(layer "F.Cu")
		(at 140.208 -114.554)
		(property "Reference" "R8120"
			(at 0 0 0)
			(layer "F.SilkS")
			(hide yes)
			(effects
				(font
					(size 1.27 1.27)
				)
			)
		)
		(property "Value" ""
			(at 0 0 0)
			(layer "F.Fab")
			(effects
				(font
					(size 1.27 1.27)
				)
			)
		)
		(duplicate_pad_numbers_are_jumpers no)
		(fp_line
			(start -0.7874 -0.4064)
			(end 0.7874 -0.4064)
			(stroke
				(width 0.1524)
				(type default)
			)
			(layer "F.SilkS")
		)
		(fp_line
			(start -0.7874 0.4064)
			(end -0.7874 -0.4064)
			(stroke
				(width 0.1524)
				(type default)
			)
			(layer "F.SilkS")
		)
		(fp_line
			(start 0.7874 -0.4064)
			(end 0.7874 0.4064)
			(stroke
				(width 0.1524)
				(type default)
			)
			(layer "F.SilkS")
		)
		(fp_line
			(start 0.7874 0.4064)
			(end -0.7874 0.4064)
			(stroke
				(width 0.1524)
				(type default)
			)
			(layer "F.SilkS")
		)
		(fp_line
			(start -0.67945 -0.305054)
			(end -0.12065 -0.305054)
			(stroke
				(width 0.1)
				(type default)
			)
			(layer "F.Fab")
		)
		(fp_line
			(start -0.67945 0.3048)
			(end -0.67945 -0.305054)
			(stroke
				(width 0.1)
				(type default)
			)
			(layer "F.Fab")
		)
		(fp_line
			(start -0.12065 -0.305054)
			(end -0.12065 -0.2794)
			(stroke
				(width 0.1)
				(type default)
			)
			(layer "F.Fab")
		)
		(fp_line
			(start -0.12065 -0.2794)
			(end 0.12065 -0.2794)
			(stroke
				(width 0.1)
				(type default)
			)
			(layer "F.Fab")
		)
		(fp_line
			(start -0.12065 0.2794)
			(end -0.12065 0.3048)
			(stroke
				(width 0.1)
				(type default)
			)
			(layer "F.Fab")
		)
		(fp_line
			(start -0.12065 0.3048)
			(end -0.67945 0.3048)
			(stroke
				(width 0.1)
				(type default)
			)
			(layer "F.Fab")
		)
		(fp_line
			(start 0.120396 0.2794)
			(end -0.12065 0.2794)
			(stroke
				(width 0.1)
				(type default)
			)
			(layer "F.Fab")
		)
		(fp_line
			(start 0.120396 0.3048)
			(end 0.120396 0.2794)
			(stroke
				(width 0.1)
				(type default)
			)
			(layer "F.Fab")
		)
		(fp_line
			(start 0.12065 -0.3048)
			(end 0.67945 -0.3048)
			(stroke
				(width 0.1)
				(type default)
			)
			(layer "F.Fab")
		)
		(fp_line
			(start 0.12065 -0.2794)
			(end 0.12065 -0.3048)
			(stroke
				(width 0.1)
				(type default)
			)
			(layer "F.Fab")
		)
		(fp_line
			(start 0.67945 -0.3048)
			(end 0.67945 0.3048)
			(stroke
				(width 0.1)
				(type default)
			)
			(layer "F.Fab")
		)
		(fp_line
			(start 0.67945 0.3048)
			(end 0.120396 0.3048)
			(stroke
				(width 0.1)
				(type default)
			)
			(layer "F.Fab")
		)
		(pad "1" smd circle
			(at -0.40005 0)
			(size 0 0)
			(layers "F.Cu" "F.Mask" "F.Paste")
			(net "P3V3_AUX")
		)
		(pad "2" smd circle
			(at 0.40005 0)
			(size 0 0)
			(layers "F.Cu" "F.Mask" "F.Paste")
			(net "UV_P2V5_COMP")
		)
	)
)
